# S9S_MB_2U (Grand Teton) — schematic netlist excerpt (pin names and nets, part order shuffled) for the footprints in the layout excerpt that follows; sources: Cadence DE-HDL packaged netlist, KiCad conversion of 03242023_DA0F0TMBIJ0_F0T_Motherboard_J_brd_V01_OCP.brd

R2499  Q_RES  33.2 1% CHIP  pkg 0402LF  page 115 : A = PWRGD_FAIL_CPU0_CD_R1 ; B = PWRGD_FAIL_CPU0_CD_R
C1244  Q_CAP  47UF 4V 20% X6S  pkg C0805  page 189 : A = P1V05_PCH_AUX ; B = GND
R1471  Q_RES  4.75K 1% CHIP  pkg 0402LF  page 208 : A = P3V3_AUX ; B = FM_CLK_CK440_SS_EN

(kicad_pcb
	(version 20260206)
	(generator "pcbnew")
	(generator_version "10.0")
	(general
		(thickness 1.6)
		(legacy_teardrops no)
	)
	(paper "A4")
	(title_block
		(title "03242023_DA0F0TMBIJ0_F0T_Motherboard_J_brd_V01_OCP.brd")
		(comment 1 "Grand Teton / footprints 5967-5969 of 6105")
	)
	(layers
		(0 "F.Cu" signal "TOP")
		(4 "In1.Cu" signal "GND")
		(6 "In2.Cu" signal "IN1")
		(8 "In3.Cu" signal "GND1")
		(10 "In4.Cu" signal "IN2")
		(12 "In5.Cu" signal "GND2")
		(14 "In6.Cu" signal "IN3")
		(16 "In7.Cu" signal "GND3")
		(18 "In8.Cu" signal "VCC")
		(20 "In9.Cu" signal "VCC1")
		(22 "In10.Cu" signal "GND4")
		(24 "In11.Cu" signal "IN4")
		(26 "In12.Cu" signal "GND5")
		(28 "In13.Cu" signal "IN5")
		(30 "In14.Cu" signal "GND6")
		(32 "In15.Cu" signal "IN6")
		(34 "In16.Cu" signal "GND7")
		(2 "B.Cu" signal "BOTTOM")
		(9 "F.Adhes" user "F.Adhesive")
		(11 "B.Adhes" user "B.Adhesive")
		(13 "F.Paste" user "Package Geometry/Pastemask Top")
		(15 "B.Paste" user "Package Geometry/Pastemask Bottom")
		(5 "F.SilkS" user "Ref Des/Silkscreen Top")
		(7 "B.SilkS" user "Ref Des/Silkscreen Bottom")
		(1 "F.Mask" user "Board Geometry/Soldermask Top")
		(3 "B.Mask" user "Board Geometry/Soldermask Bottom")
		(17 "Dwgs.User" user "User.Drawings")
		(19 "Cmts.User" user "User.Comments")
		(21 "Eco1.User" user "User.Eco1")
		(23 "Eco2.User" user "User.Eco2")
		(25 "Edge.Cuts" user "Board Geometry/Outline")
		(27 "Margin" user)
		(31 "F.CrtYd" user "Package Geometry/Place Bound Top")
		(29 "B.CrtYd" user "Package Geometry/Place Bound Bottom")
		(35 "F.Fab" user "Ref Des/Assembly Top")
		(33 "B.Fab" user "Ref Des/Assembly Bottom")
	)
	(footprint ""
		(layer "B.Cu")
		(at 288.376106 -313.866784 90)
		(property "Reference" "R2499"
			(at 0 0 90)
			(layer "B.SilkS")
			(hide yes)
			(effects
				(font
					(size 1.27 1.27)
				)
				(justify mirror)
			)
		)
		(property "Value" ""
			(at 0 0 90)
			(layer "B.Fab")
			(effects
				(font
					(size 1.27 1.27)
				)
				(justify mirror)
			)
		)
		(duplicate_pad_numbers_are_jumpers no)
		(fp_line
			(start 0.7874 -0.4064)
			(end -0.7874 -0.4064)
			(stroke
				(width 0.1524)
				(type default)
			)
			(layer "B.SilkS")
		)
		(fp_line
			(start -0.7874 -0.4064)
			(end -0.7874 0.4064)
			(stroke
				(width 0.1524)
				(type default)
			)
			(layer "B.SilkS")
		)
		(fp_line
			(start 0.7874 0.4064)
			(end 0.7874 -0.4064)
			(stroke
				(width 0.1524)
				(type default)
			)
			(layer "B.SilkS")
		)
		(fp_line
			(start -0.7874 0.4064)
			(end 0.7874 0.4064)
			(stroke
				(width 0.1524)
				(type default)
			)
			(layer "B.SilkS")
		)
		(fp_line
			(start 0.67945 -0.305054)
			(end 0.12065 -0.305054)
			(stroke
				(width 0.1)
				(type default)
			)
			(layer "B.Fab")
		)
		(fp_line
			(start 0.12065 -0.305054)
			(end 0.12065 -0.2794)
			(stroke
				(width 0.1)
				(type default)
			)
			(layer "B.Fab")
		)
		(fp_line
			(start -0.12065 -0.3048)
			(end -0.67945 -0.3048)
			(stroke
				(width 0.1)
				(type default)
			)
			(layer "B.Fab")
		)
		(fp_line
			(start -0.67945 -0.3048)
			(end -0.67945 0.3048)
			(stroke
				(width 0.1)
				(type default)
			)
			(layer "B.Fab")
		)
		(fp_line
			(start 0.12065 -0.2794)
			(end -0.12065 -0.2794)
			(stroke
				(width 0.1)
				(type default)
			)
			(layer "B.Fab")
		)
		(fp_line
			(start -0.12065 -0.2794)
			(end -0.12065 -0.3048)
			(stroke
				(width 0.1)
				(type default)
			)
			(layer "B.Fab")
		)
		(fp_line
			(start 0.12065 0.2794)
			(end 0.12065 0.3048)
			(stroke
				(width 0.1)
				(type default)
			)
			(layer "B.Fab")
		)
		(fp_line
			(start -0.120396 0.2794)
			(end 0.12065 0.2794)
			(stroke
				(width 0.1)
				(type default)
			)
			(layer "B.Fab")
		)
		(fp_line
			(start 0.67945 0.3048)
			(end 0.67945 -0.305054)
			(stroke
				(width 0.1)
				(type default)
			)
			(layer "B.Fab")
		)
		(fp_line
			(start 0.12065 0.3048)
			(end 0.67945 0.3048)
			(stroke
				(width 0.1)
				(type default)
			)
			(layer "B.Fab")
		)
		(fp_line
			(start -0.120396 0.3048)
			(end -0.120396 0.2794)
			(stroke
				(width 0.1)
				(type default)
			)
			(layer "B.Fab")
		)
		(fp_line
			(start -0.67945 0.3048)
			(end -0.120396 0.3048)
			(stroke
				(width 0.1)
				(type default)
			)
			(layer "B.Fab")
		)
		(pad "1" smd circle
			(at 0.40005 0 270)
			(size 0 0)
			(layers "B.Cu" "B.Mask" "B.Paste")
			(net "PWRGD_FAIL_CPU0_CD_R1")
		)
		(pad "2" smd circle
			(at -0.40005 0 270)
			(size 0 0)
			(layers "B.Cu" "B.Mask" "B.Paste")
			(net "PWRGD_FAIL_CPU0_CD_R")
		)
	)
	(footprint ""
		(layer "B.Cu")
		(at 302.151542 -50.923444 180)
		(property "Reference" "C1244"
			(at 0 0 0)
			(layer "B.SilkS")
			(hide yes)
			(effects
				(font
					(size 1.27 1.27)
				)
				(justify mirror)
			)
		)
		(property "Value" ""
			(at 0 0 0)
			(layer "B.Fab")
			(effects
				(font
					(size 1.27 1.27)
				)
				(justify mirror)
			)
		)
		(duplicate_pad_numbers_are_jumpers no)
		(fp_line
			(start 1.524 0.762)
			(end 1.524 -0.762)
			(stroke
				(width 0.1524)
				(type default)
			)
			(layer "B.SilkS")
		)
		(fp_line
			(start 1.524 -0.762)
			(end -1.524 -0.762)
			(stroke
				(width 0.1524)
				(type default)
			)
			(layer "B.SilkS")
		)
		(fp_line
			(start -1.524 0.762)
			(end 1.524 0.762)
			(stroke
				(width 0.1524)
				(type default)
			)
			(layer "B.SilkS")
		)
		(fp_line
			(start -1.524 -0.762)
			(end -1.524 0.762)
			(stroke
				(width 0.1524)
				(type default)
			)
			(layer "B.SilkS")
		)
		(fp_line
			(start 1.1049 0.724916)
			(end -1.1049 0.724916)
			(stroke
				(width 0.1)
				(type default)
			)
			(layer "B.Fab")
		)
		(fp_line
			(start 1.1049 -0.724916)
			(end 1.1049 0.724916)
			(stroke
				(width 0.1)
				(type default)
			)
			(layer "B.Fab")
		)
		(fp_line
			(start -1.1049 0.724916)
			(end -1.1049 -0.724916)
			(stroke
				(width 0.1)
				(type default)
			)
			(layer "B.Fab")
		)
		(fp_line
			(start -1.1049 -0.724916)
			(end 1.1049 -0.724916)
			(stroke
				(width 0.1)
				(type default)
			)
			(layer "B.Fab")
		)
		(pad "1" smd rect
			(at 0.889 0 180)
			(size 1.016 1.27)
			(layers "B.Cu" "B.Mask" "B.Paste")
			(net "P1V05_PCH_AUX")
		)
		(pad "2" smd rect
			(at -0.889 0 180)
			(size 1.016 1.27)
			(layers "B.Cu" "B.Mask" "B.Paste")
			(net "GND")
		)
	)
	(footprint ""
		(layer "B.Cu")
		(at 254.268986 -86.824566)
		(property "Reference" "R1471"
			(at 0 0 0)
			(layer "B.SilkS")
			(hide yes)
			(effects
				(font
					(size 1.27 1.27)
				)
				(justify mirror)
			)
		)
		(property "Value" ""
			(at 0 0 0)
			(layer "B.Fab")
			(effects
				(font
					(size 1.27 1.27)
				)
				(justify mirror)
			)
		)
		(duplicate_pad_numbers_are_jumpers no)
		(fp_line
			(start -0.7874 -0.4064)
			(end -0.7874 0.4064)
			(stroke
				(width 0.1524)
				(type default)
			)
			(layer "B.SilkS")
		)
		(fp_line
			(start -0.7874 0.4064)
			(end 0.7874 0.4064)
			(stroke
				(width 0.1524)
				(type default)
			)
			(layer "B.SilkS")
		)
		(fp_line
			(start 0.7874 -0.4064)
			(end -0.7874 -0.4064)
			(stroke
				(width 0.1524)
				(type default)
			)
			(layer "B.SilkS")
		)
		(fp_line
			(start 0.7874 0.4064)
			(end 0.7874 -0.4064)
			(stroke
				(width 0.1524)
				(type default)
			)
			(layer "B.SilkS")
		)
		(fp_line
			(start -0.67945 -0.3048)
			(end -0.67945 0.3048)
			(stroke
				(width 0.1)
				(type default)
			)
			(layer "B.Fab")
		)
		(fp_line
			(start -0.67945 0.3048)
			(end -0.120396 0.3048)
			(stroke
				(width 0.1)
				(type default)
			)
			(layer "B.Fab")
		)
		(fp_line
			(start -0.12065 -0.3048)
			(end -0.67945 -0.3048)
			(stroke
				(width 0.1)
				(type default)
			)
			(layer "B.Fab")
		)
		(fp_line
			(start -0.12065 -0.2794)
			(end -0.12065 -0.3048)
			(stroke
				(width 0.1)
				(type default)
			)
			(layer "B.Fab")
		)
		(fp_line
			(start -0.120396 0.2794)
			(end 0.12065 0.2794)
			(stroke
				(width 0.1)
				(type default)
			)
			(layer "B.Fab")
		)
		(fp_line
			(start -0.120396 0.3048)
			(end -0.120396 0.2794)
			(stroke
				(width 0.1)
				(type default)
			)
			(layer "B.Fab")
		)
		(fp_line
			(start 0.12065 -0.305054)
			(end 0.12065 -0.2794)
			(stroke
				(width 0.1)
				(type default)
			)
			(layer "B.Fab")
		)
		(fp_line
			(start 0.12065 -0.2794)
			(end -0.12065 -0.2794)
			(stroke
				(width 0.1)
				(type default)
			)
			(layer "B.Fab")
		)
		(fp_line
			(start 0.12065 0.2794)
			(end 0.12065 0.3048)
			(stroke
				(width 0.1)
				(type default)
			)
			(layer "B.Fab")
		)
		(fp_line
			(start 0.12065 0.3048)
			(end 0.67945 0.3048)
			(stroke
				(width 0.1)
				(type default)
			)
			(layer "B.Fab")
		)
		(fp_line
			(start 0.67945 -0.305054)
			(end 0.12065 -0.305054)
			(stroke
				(width 0.1)
				(type default)
			)
			(layer "B.Fab")
		)
		(fp_line
			(start 0.67945 0.3048)
			(end 0.67945 -0.305054)
			(stroke
				(width 0.1)
				(type default)
			)
			(layer "B.Fab")
		)
		(pad "1" smd circle
			(at 0.40005 0 180)
			(size 0 0)
			(layers "B.Cu" "B.Mask" "B.Paste")
			(net "P3V3_AUX")
		)
		(pad "2" smd circle
			(at -0.40005 0 180)
			(size 0 0)
			(layers "B.Cu" "B.Mask" "B.Paste")
			(net "FM_CLK_CK440_SS_EN")
		)
	)
)
